# BASEBOARD_FAB2 (Tioga Pass) — schematic netlist excerpt (pin names and nets, part order shuffled) for the footprints in the layout excerpt that follows; sources: Cadence DE-HDL packaged netlist, KiCad conversion of Wiwynn_Tioga_Pass_MB.brd

C1M29  CAP_A  0.1UF 16V 10% X7R  pkg 0402V  page 113 : A = P1V8_MCP_CPU0 ; B = GND
R25W107  RES  4.75K 1% CHIP  pkg 0402  page 150 : A = P3V3_STBY ; B = RMII_BMC_OCP_TXD0_R
CT19  CAP  1000PF 50V 10% X7R  pkg 0402LF  page 208 : A = A_TSENSE_PVCCIN_CPU1 ; B = GND

(kicad_pcb
	(version 20260206)
	(generator "pcbnew")
	(generator_version "10.0")
	(general
		(thickness 1.6)
		(legacy_teardrops no)
	)
	(paper "A4")
	(title_block
		(title "Wiwynn_Tioga_Pass_MB.brd")
		(comment 1 "Tioga Pass / footprints 4085-4087 of 4770")
	)
	(layers
		(0 "F.Cu" signal "TOP")
		(4 "In1.Cu" signal "L2GND")
		(6 "In2.Cu" signal "L3")
		(8 "In3.Cu" signal "L4GND")
		(10 "In4.Cu" signal "L5")
		(12 "In5.Cu" signal "L6GND")
		(14 "In6.Cu" signal "L7VCC")
		(16 "In7.Cu" signal "L8VCC")
		(18 "In8.Cu" signal "L9GND")
		(20 "In9.Cu" signal "L10")
		(22 "In10.Cu" signal "L11GND")
		(24 "In11.Cu" signal "L12")
		(26 "In12.Cu" signal "L13GND")
		(2 "B.Cu" signal "BOTTOM")
		(9 "F.Adhes" user "F.Adhesive")
		(11 "B.Adhes" user "B.Adhesive")
		(13 "F.Paste" user "Package Geometry/Pastemask Top")
		(15 "B.Paste" user "Package Geometry/Pastemask Bottom")
		(5 "F.SilkS" user "Ref Des/Silkscreen Top")
		(7 "B.SilkS" user "Ref Des/Silkscreen Bottom")
		(1 "F.Mask" user "Board Geometry/Soldermask Top")
		(3 "B.Mask" user "Board Geometry/Soldermask Bottom")
		(17 "Dwgs.User" user "User.Drawings")
		(19 "Cmts.User" user "User.Comments")
		(21 "Eco1.User" user "User.Eco1")
		(23 "Eco2.User" user "User.Eco2")
		(25 "Edge.Cuts" user "Board Geometry/Outline")
		(27 "Margin" user)
		(31 "F.CrtYd" user "Package Geometry/Place Bound Top")
		(29 "B.CrtYd" user "Package Geometry/Place Bound Bottom")
		(35 "F.Fab" user "Ref Des/Assembly Top")
		(33 "B.Fab" user "Ref Des/Assembly Bottom")
	)
	(footprint ""
		(layer "B.Cu")
		(at 471.14206 -130.0734)
		(property "Reference" "C1M29"
			(at 0 0 0)
			(layer "B.SilkS")
			(hide yes)
			(effects
				(font
					(size 1.27 1.27)
				)
				(justify mirror)
			)
		)
		(property "Value" ""
			(at 0 0 0)
			(layer "B.Fab")
			(effects
				(font
					(size 1.27 1.27)
				)
				(justify mirror)
			)
		)
		(duplicate_pad_numbers_are_jumpers no)
		(fp_poly
			(pts
				(xy -0.3048 -0.1016) (xy -0.3048 0.9906) (xy 0.3048 0.9906) (xy 0.3048 -0.1016)
			)
			(stroke
				(width 0)
				(type default)
			)
			(fill no)
			(layer "B.CrtYd")
		)
		(fp_line
			(start -0.3048 -0.1016)
			(end 0.3048 -0.1016)
			(stroke
				(width 0.1)
				(type default)
			)
			(layer "B.Fab")
		)
		(fp_line
			(start -0.3048 0.9906)
			(end -0.3048 -0.1016)
			(stroke
				(width 0.1)
				(type default)
			)
			(layer "B.Fab")
		)
		(fp_line
			(start 0.3048 -0.1016)
			(end 0.3048 0.9906)
			(stroke
				(width 0.1)
				(type default)
			)
			(layer "B.Fab")
		)
		(fp_line
			(start 0.3048 0.9906)
			(end -0.3048 0.9906)
			(stroke
				(width 0.1)
				(type default)
			)
			(layer "B.Fab")
		)
		(pad "1" smd rect
			(at 0 0 180)
			(size 0.508 0.508)
			(layers "B.Cu" "B.Mask" "B.Paste")
			(net "P1V8_MCP_CPU0")
		)
		(pad "2" smd rect
			(at 0 0.889 180)
			(size 0.508 0.508)
			(layers "B.Cu" "B.Mask" "B.Paste")
			(net "GND")
		)
		(zone
			(layer "B.Cu")
			(hatch none 0.5)
			(connect_pads
				(clearance 0)
			)
			(min_thickness 0.25)
			(keepout
				(tracks allowed)
				(vias not_allowed)
				(pads allowed)
				(copperpour not_allowed)
				(footprints allowed)
			)
			(placement
				(enabled no)
				(sheetname "")
			)
			(fill
				(thermal_gap 0.5)
				(thermal_bridge_width 0.5)
				(island_removal_mode 0)
			)
			(polygon
				(pts
					(xy 471.39606 -129.8194) (xy 470.88806 -129.8194) (xy 470.88806 -129.4384) (xy 471.39606 -129.4384)
				)
			)
		)
		(zone
			(layer "B.Cu")
			(hatch none 0.5)
			(connect_pads
				(clearance 0)
			)
			(min_thickness 0.25)
			(keepout
				(tracks not_allowed)
				(vias allowed)
				(pads allowed)
				(copperpour not_allowed)
				(footprints allowed)
			)
			(placement
				(enabled no)
				(sheetname "")
			)
			(fill
				(thermal_gap 0.5)
				(thermal_bridge_width 0.5)
				(island_removal_mode 0)
			)
			(polygon
				(pts
					(xy 471.39606 -129.4384) (xy 470.88806 -129.4384) (xy 470.88806 -129.8194) (xy 471.39606 -129.8194)
				)
			)
		)
	)
	(footprint ""
		(layer "B.Cu")
		(at 31.0134 -80.4926 180)
		(property "Reference" "CT19"
			(at 0.8382 -0.84963 180)
			(unlocked yes)
			(layer "B.SilkS")
			(effects
				(font
					(size 0.7874 0.5842)
					(thickness 0.1524)
				)
				(justify left mirror)
			)
		)
		(property "Value" ""
			(at 0 0 0)
			(layer "B.Fab")
			(effects
				(font
					(size 1.27 1.27)
				)
				(justify mirror)
			)
		)
		(duplicate_pad_numbers_are_jumpers no)
		(fp_poly
			(pts
				(xy -0.3048 -0.1016) (xy -0.3048 0.9906) (xy 0.3048 0.9906) (xy 0.3048 -0.1016)
			)
			(stroke
				(width 0)
				(type default)
			)
			(fill no)
			(layer "B.CrtYd")
		)
		(fp_line
			(start 0.3048 0.9906)
			(end -0.3048 0.9906)
			(stroke
				(width 0.1)
				(type default)
			)
			(layer "B.Fab")
		)
		(fp_line
			(start 0.3048 -0.1016)
			(end 0.3048 0.9906)
			(stroke
				(width 0.1)
				(type default)
			)
			(layer "B.Fab")
		)
		(fp_line
			(start -0.3048 0.9906)
			(end -0.3048 -0.1016)
			(stroke
				(width 0.1)
				(type default)
			)
			(layer "B.Fab")
		)
		(fp_line
			(start -0.3048 -0.1016)
			(end 0.3048 -0.1016)
			(stroke
				(width 0.1)
				(type default)
			)
			(layer "B.Fab")
		)
		(pad "1" smd rect
			(at 0 0)
			(size 0.508 0.508)
			(layers "B.Cu" "B.Mask" "B.Paste")
			(net "A_TSENSE_PVCCIN_CPU1")
		)
		(pad "2" smd rect
			(at 0 0.889)
			(size 0.508 0.508)
			(layers "B.Cu" "B.Mask" "B.Paste")
			(net "GND")
		)
		(zone
			(layer "B.Cu")
			(hatch none 0.5)
			(connect_pads
				(clearance 0)
			)
			(min_thickness 0.25)
			(keepout
				(tracks not_allowed)
				(vias allowed)
				(pads allowed)
				(copperpour not_allowed)
				(footprints allowed)
			)
			(placement
				(enabled no)
				(sheetname "")
			)
			(fill
				(thermal_gap 0.5)
				(thermal_bridge_width 0.5)
				(island_removal_mode 0)
			)
			(polygon
				(pts
					(xy 30.7594 -81.1276) (xy 31.2674 -81.1276) (xy 31.2674 -80.7466) (xy 30.7594 -80.7466)
				)
			)
		)
		(zone
			(layer "B.Cu")
			(hatch none 0.5)
			(connect_pads
				(clearance 0)
			)
			(min_thickness 0.25)
			(keepout
				(tracks allowed)
				(vias not_allowed)
				(pads allowed)
				(copperpour not_allowed)
				(footprints allowed)
			)
			(placement
				(enabled no)
				(sheetname "")
			)
			(fill
				(thermal_gap 0.5)
				(thermal_bridge_width 0.5)
				(island_removal_mode 0)
			)
			(polygon
				(pts
					(xy 30.7594 -80.7466) (xy 31.2674 -80.7466) (xy 31.2674 -81.1276) (xy 30.7594 -81.1276)
				)
			)
		)
	)
	(footprint ""
		(layer "B.Cu")
		(at 401.599146 -35.569652 90)
		(property "Reference" "R25W107"
			(at 0.8382 -0.67818 90)
			(unlocked yes)
			(layer "B.SilkS")
			(effects
				(font
					(size 0.4064 0.254)
					(thickness 0.1524)
				)
				(justify left mirror)
			)
		)
		(property "Value" ""
			(at 0 0 90)
			(layer "B.Fab")
			(effects
				(font
					(size 1.27 1.27)
				)
				(justify mirror)
			)
		)
		(duplicate_pad_numbers_are_jumpers no)
		(fp_poly
			(pts
				(xy 0.2794 -0.1016) (xy -0.2794 -0.1016) (xy -0.2794 0.9906) (xy 0.2794 0.9906)
			)
			(stroke
				(width 0)
				(type default)
			)
			(fill no)
			(layer "B.CrtYd")
		)
		(fp_line
			(start 0.2794 -0.1016)
			(end 0.2794 0.9906)
			(stroke
				(width 0.1)
				(type default)
			)
			(layer "B.Fab")
		)
		(fp_line
			(start -0.2794 -0.1016)
			(end 0.2794 -0.1016)
			(stroke
				(width 0.1)
				(type default)
			)
			(layer "B.Fab")
		)
		(fp_line
			(start 0.2794 0.9906)
			(end -0.2794 0.9906)
			(stroke
				(width 0.1)
				(type default)
			)
			(layer "B.Fab")
		)
		(fp_line
			(start -0.2794 0.9906)
			(end -0.2794 -0.1016)
			(stroke
				(width 0.1)
				(type default)
			)
			(layer "B.Fab")
		)
		(pad "1" smd rect
			(at 0 0 270)
			(size 0.508 0.508)
			(layers "B.Cu" "B.Mask" "B.Paste")
			(net "P3V3_STBY")
		)
		(pad "2" smd rect
			(at 0 0.889 270)
			(size 0.508 0.508)
			(layers "B.Cu" "B.Mask" "B.Paste")
			(net "RMII_BMC_OCP_TXD0_R")
		)
		(zone
			(layer "B.Cu")
			(hatch none 0.5)
			(connect_pads
				(clearance 0)
			)
			(min_thickness 0.25)
			(keepout
				(tracks allowed)
				(vias not_allowed)
				(pads allowed)
				(copperpour not_allowed)
				(footprints allowed)
			)
			(placement
				(enabled no)
				(sheetname "")
			)
			(fill
				(thermal_gap 0.5)
				(thermal_bridge_width 0.5)
				(island_removal_mode 0)
			)
			(polygon
				(pts
					(xy 401.853146 -35.823652) (xy 401.853146 -35.315652) (xy 402.234146 -35.315652) (xy 402.234146 -35.823652)
				)
			)
		)
		(zone
			(layer "B.Cu")
			(hatch none 0.5)
			(connect_pads
				(clearance 0)
			)
			(min_thickness 0.25)
			(keepout
				(tracks not_allowed)
				(vias allowed)
				(pads allowed)
				(copperpour not_allowed)
				(footprints allowed)
			)
			(placement
				(enabled no)
				(sheetname "")
			)
			(fill
				(thermal_gap 0.5)
				(thermal_bridge_width 0.5)
				(island_removal_mode 0)
			)
			(polygon
				(pts
					(xy 402.234146 -35.823652) (xy 402.234146 -35.315652) (xy 401.853146 -35.315652) (xy 401.853146 -35.823652)
				)
			)
		)
	)
)
